# S9S_MB_2U (Grand Teton) — schematic netlist excerpt (pin names and nets, part order shuffled) for the footprints in the layout excerpt that follows; sources: Cadence DE-HDL packaged netlist, KiCad conversion of 03242023_DA0F0TMBIJ0_F0T_Motherboard_J_brd_V01_OCP.brd

R3254  Q_RES  0 5% EMPTY  pkg 0402LF  page 240 : A = TP_PCIE_HPM_TXP<3> ; B = LED_HDD_ACTIVITY_B_N
R4631  Q_RES  0 5% CHIP  pkg 0402LF  page 248 : A = JTAG_BMC_SW_TDI_R ; B = JTAG_BMC_SW_TDI

(kicad_pcb
	(version 20260206)
	(generator "pcbnew")
	(generator_version "10.0")
	(general
		(thickness 1.6)
		(legacy_teardrops no)
	)
	(paper "A4")
	(title_block
		(title "03242023_DA0F0TMBIJ0_F0T_Motherboard_J_brd_V01_OCP.brd")
		(comment 1 "Grand Teton / footprints 854-855 of 6105")
	)
	(layers
		(0 "F.Cu" signal "TOP")
		(4 "In1.Cu" signal "GND")
		(6 "In2.Cu" signal "IN1")
		(8 "In3.Cu" signal "GND1")
		(10 "In4.Cu" signal "IN2")
		(12 "In5.Cu" signal "GND2")
		(14 "In6.Cu" signal "IN3")
		(16 "In7.Cu" signal "GND3")
		(18 "In8.Cu" signal "VCC")
		(20 "In9.Cu" signal "VCC1")
		(22 "In10.Cu" signal "GND4")
		(24 "In11.Cu" signal "IN4")
		(26 "In12.Cu" signal "GND5")
		(28 "In13.Cu" signal "IN5")
		(30 "In14.Cu" signal "GND6")
		(32 "In15.Cu" signal "IN6")
		(34 "In16.Cu" signal "GND7")
		(2 "B.Cu" signal "BOTTOM")
		(9 "F.Adhes" user "F.Adhesive")
		(11 "B.Adhes" user "B.Adhesive")
		(13 "F.Paste" user "Package Geometry/Pastemask Top")
		(15 "B.Paste" user "Package Geometry/Pastemask Bottom")
		(5 "F.SilkS" user "Ref Des/Silkscreen Top")
		(7 "B.SilkS" user "Ref Des/Silkscreen Bottom")
		(1 "F.Mask" user "Board Geometry/Soldermask Top")
		(3 "B.Mask" user "Board Geometry/Soldermask Bottom")
		(17 "Dwgs.User" user "User.Drawings")
		(19 "Cmts.User" user "User.Comments")
		(21 "Eco1.User" user "User.Eco1")
		(23 "Eco2.User" user "User.Eco2")
		(25 "Edge.Cuts" user "Board Geometry/Outline")
		(27 "Margin" user)
		(31 "F.CrtYd" user "Package Geometry/Place Bound Top")
		(29 "B.CrtYd" user "Package Geometry/Place Bound Bottom")
		(35 "F.Fab" user "Ref Des/Assembly Top")
		(33 "B.Fab" user "Ref Des/Assembly Bottom")
	)
	(footprint ""
		(layer "F.Cu")
		(at 131.32308 -21.554948 90)
		(property "Reference" "R3254"
			(at 0 0 90)
			(layer "F.SilkS")
			(hide yes)
			(effects
				(font
					(size 1.27 1.27)
				)
			)
		)
		(property "Value" ""
			(at 0 0 90)
			(layer "F.Fab")
			(effects
				(font
					(size 1.27 1.27)
				)
			)
		)
		(duplicate_pad_numbers_are_jumpers no)
		(fp_line
			(start 0.7874 -0.4064)
			(end 0.7874 0.4064)
			(stroke
				(width 0.1524)
				(type default)
			)
			(layer "F.SilkS")
		)
		(fp_line
			(start -0.7874 -0.4064)
			(end 0.7874 -0.4064)
			(stroke
				(width 0.1524)
				(type default)
			)
			(layer "F.SilkS")
		)
		(fp_line
			(start 0.7874 0.4064)
			(end -0.7874 0.4064)
			(stroke
				(width 0.1524)
				(type default)
			)
			(layer "F.SilkS")
		)
		(fp_line
			(start -0.7874 0.4064)
			(end -0.7874 -0.4064)
			(stroke
				(width 0.1524)
				(type default)
			)
			(layer "F.SilkS")
		)
		(fp_line
			(start -0.12065 -0.305054)
			(end -0.12065 -0.2794)
			(stroke
				(width 0.1)
				(type default)
			)
			(layer "F.Fab")
		)
		(fp_line
			(start -0.67945 -0.305054)
			(end -0.12065 -0.305054)
			(stroke
				(width 0.1)
				(type default)
			)
			(layer "F.Fab")
		)
		(fp_line
			(start 0.67945 -0.3048)
			(end 0.67945 0.3048)
			(stroke
				(width 0.1)
				(type default)
			)
			(layer "F.Fab")
		)
		(fp_line
			(start 0.12065 -0.3048)
			(end 0.67945 -0.3048)
			(stroke
				(width 0.1)
				(type default)
			)
			(layer "F.Fab")
		)
		(fp_line
			(start 0.12065 -0.2794)
			(end 0.12065 -0.3048)
			(stroke
				(width 0.1)
				(type default)
			)
			(layer "F.Fab")
		)
		(fp_line
			(start -0.12065 -0.2794)
			(end 0.12065 -0.2794)
			(stroke
				(width 0.1)
				(type default)
			)
			(layer "F.Fab")
		)
		(fp_line
			(start 0.120396 0.2794)
			(end -0.12065 0.2794)
			(stroke
				(width 0.1)
				(type default)
			)
			(layer "F.Fab")
		)
		(fp_line
			(start -0.12065 0.2794)
			(end -0.12065 0.3048)
			(stroke
				(width 0.1)
				(type default)
			)
			(layer "F.Fab")
		)
		(fp_line
			(start 0.67945 0.3048)
			(end 0.120396 0.3048)
			(stroke
				(width 0.1)
				(type default)
			)
			(layer "F.Fab")
		)
		(fp_line
			(start 0.120396 0.3048)
			(end 0.120396 0.2794)
			(stroke
				(width 0.1)
				(type default)
			)
			(layer "F.Fab")
		)
		(fp_line
			(start -0.12065 0.3048)
			(end -0.67945 0.3048)
			(stroke
				(width 0.1)
				(type default)
			)
			(layer "F.Fab")
		)
		(fp_line
			(start -0.67945 0.3048)
			(end -0.67945 -0.305054)
			(stroke
				(width 0.1)
				(type default)
			)
			(layer "F.Fab")
		)
		(pad "1" smd circle
			(at -0.40005 0 90)
			(size 0 0)
			(layers "F.Cu" "F.Mask" "F.Paste")
			(net "TP_PCIE_HPM_TXP<3>")
		)
		(pad "2" smd circle
			(at 0.40005 0 90)
			(size 0 0)
			(layers "F.Cu" "F.Mask" "F.Paste")
			(net "LED_HDD_ACTIVITY_B_N")
		)
	)
	(footprint ""
		(layer "F.Cu")
		(at 129.159 -53.304948)
		(property "Reference" "R4631"
			(at 0 0 0)
			(layer "F.SilkS")
			(hide yes)
			(effects
				(font
					(size 1.27 1.27)
				)
			)
		)
		(property "Value" ""
			(at 0 0 0)
			(layer "F.Fab")
			(effects
				(font
					(size 1.27 1.27)
				)
			)
		)
		(duplicate_pad_numbers_are_jumpers no)
		(fp_line
			(start -0.7874 -0.4064)
			(end 0.7874 -0.4064)
			(stroke
				(width 0.1524)
				(type default)
			)
			(layer "F.SilkS")
		)
		(fp_line
			(start -0.7874 0.4064)
			(end -0.7874 -0.4064)
			(stroke
				(width 0.1524)
				(type default)
			)
			(layer "F.SilkS")
		)
		(fp_line
			(start 0.7874 -0.4064)
			(end 0.7874 0.4064)
			(stroke
				(width 0.1524)
				(type default)
			)
			(layer "F.SilkS")
		)
		(fp_line
			(start 0.7874 0.4064)
			(end -0.7874 0.4064)
			(stroke
				(width 0.1524)
				(type default)
			)
			(layer "F.SilkS")
		)
		(fp_line
			(start -0.67945 -0.305054)
			(end -0.12065 -0.305054)
			(stroke
				(width 0.1)
				(type default)
			)
			(layer "F.Fab")
		)
		(fp_line
			(start -0.67945 0.3048)
			(end -0.67945 -0.305054)
			(stroke
				(width 0.1)
				(type default)
			)
			(layer "F.Fab")
		)
		(fp_line
			(start -0.12065 -0.305054)
			(end -0.12065 -0.2794)
			(stroke
				(width 0.1)
				(type default)
			)
			(layer "F.Fab")
		)
		(fp_line
			(start -0.12065 -0.2794)
			(end 0.12065 -0.2794)
			(stroke
				(width 0.1)
				(type default)
			)
			(layer "F.Fab")
		)
		(fp_line
			(start -0.12065 0.2794)
			(end -0.12065 0.3048)
			(stroke
				(width 0.1)
				(type default)
			)
			(layer "F.Fab")
		)
		(fp_line
			(start -0.12065 0.3048)
			(end -0.67945 0.3048)
			(stroke
				(width 0.1)
				(type default)
			)
			(layer "F.Fab")
		)
		(fp_line
			(start 0.120396 0.2794)
			(end -0.12065 0.2794)
			(stroke
				(width 0.1)
				(type default)
			)
			(layer "F.Fab")
		)
		(fp_line
			(start 0.120396 0.3048)
			(end 0.120396 0.2794)
			(stroke
				(width 0.1)
				(type default)
			)
			(layer "F.Fab")
		)
		(fp_line
			(start 0.12065 -0.3048)
			(end 0.67945 -0.3048)
			(stroke
				(width 0.1)
				(type default)
			)
			(layer "F.Fab")
		)
		(fp_line
			(start 0.12065 -0.2794)
			(end 0.12065 -0.3048)
			(stroke
				(width 0.1)
				(type default)
			)
			(layer "F.Fab")
		)
		(fp_line
			(start 0.67945 -0.3048)
			(end 0.67945 0.3048)
			(stroke
				(width 0.1)
				(type default)
			)
			(layer "F.Fab")
		)
		(fp_line
			(start 0.67945 0.3048)
			(end 0.120396 0.3048)
			(stroke
				(width 0.1)
				(type default)
			)
			(layer "F.Fab")
		)
		(pad "1" smd circle
			(at -0.40005 0)
			(size 0 0)
			(layers "F.Cu" "F.Mask" "F.Paste")
			(net "JTAG_BMC_SW_TDI_R")
		)
		(pad "2" smd circle
			(at 0.40005 0)
			(size 0 0)
			(layers "F.Cu" "F.Mask" "F.Paste")
			(net "JTAG_BMC_SW_TDI")
		)
	)
)
